# S9S_MB_2U (Grand Teton) — schematic netlist excerpt (pin names and nets, part order shuffled) for the footprints in the layout excerpt that follows; sources: Cadence DE-HDL packaged netlist, KiCad conversion of 03242023_DA0F0TMBIJ0_F0T_Motherboard_J_brd_V01_OCP.brd

C2290  Q_CAP  0.1UF 6.3V 10% X6S  pkg C0201  page 169 : A = USB3_PCH_TX_BUF_DN<4> ; B = USB3_PCH_TX_BUF_C_DN<4>
R498  Q_RES  10K 1% CHIP  pkg 0402LF  page 185 : A = P3V3_AUX ; B = FM_PCH_PRSNT_N
R559  Q_RES  100 1% CHIP  pkg 0402LF  page 45 : A = SVID_DIO1_CPU1_R ; B = PVNN_TERM_CPU1

(kicad_pcb
	(version 20260206)
	(generator "pcbnew")
	(generator_version "10.0")
	(general
		(thickness 1.6)
		(legacy_teardrops no)
	)
	(paper "A4")
	(title_block
		(title "03242023_DA0F0TMBIJ0_F0T_Motherboard_J_brd_V01_OCP.brd")
		(comment 1 "Grand Teton / footprints 5574-5576 of 6105")
	)
	(layers
		(0 "F.Cu" signal "TOP")
		(4 "In1.Cu" signal "GND")
		(6 "In2.Cu" signal "IN1")
		(8 "In3.Cu" signal "GND1")
		(10 "In4.Cu" signal "IN2")
		(12 "In5.Cu" signal "GND2")
		(14 "In6.Cu" signal "IN3")
		(16 "In7.Cu" signal "GND3")
		(18 "In8.Cu" signal "VCC")
		(20 "In9.Cu" signal "VCC1")
		(22 "In10.Cu" signal "GND4")
		(24 "In11.Cu" signal "IN4")
		(26 "In12.Cu" signal "GND5")
		(28 "In13.Cu" signal "IN5")
		(30 "In14.Cu" signal "GND6")
		(32 "In15.Cu" signal "IN6")
		(34 "In16.Cu" signal "GND7")
		(2 "B.Cu" signal "BOTTOM")
		(9 "F.Adhes" user "F.Adhesive")
		(11 "B.Adhes" user "B.Adhesive")
		(13 "F.Paste" user "Package Geometry/Pastemask Top")
		(15 "B.Paste" user "Package Geometry/Pastemask Bottom")
		(5 "F.SilkS" user "Ref Des/Silkscreen Top")
		(7 "B.SilkS" user "Ref Des/Silkscreen Bottom")
		(1 "F.Mask" user "Board Geometry/Soldermask Top")
		(3 "B.Mask" user "Board Geometry/Soldermask Bottom")
		(17 "Dwgs.User" user "User.Drawings")
		(19 "Cmts.User" user "User.Comments")
		(21 "Eco1.User" user "User.Eco1")
		(23 "Eco2.User" user "User.Eco2")
		(25 "Edge.Cuts" user "Board Geometry/Outline")
		(27 "Margin" user)
		(31 "F.CrtYd" user "Package Geometry/Place Bound Top")
		(29 "B.CrtYd" user "Package Geometry/Place Bound Bottom")
		(35 "F.Fab" user "Ref Des/Assembly Top")
		(33 "B.Fab" user "Ref Des/Assembly Bottom")
	)
	(footprint ""
		(layer "B.Cu")
		(at 352.68027 -59.737752)
		(property "Reference" "R498"
			(at 0 0 0)
			(layer "B.SilkS")
			(hide yes)
			(effects
				(font
					(size 1.27 1.27)
				)
				(justify mirror)
			)
		)
		(property "Value" ""
			(at 0 0 0)
			(layer "B.Fab")
			(effects
				(font
					(size 1.27 1.27)
				)
				(justify mirror)
			)
		)
		(duplicate_pad_numbers_are_jumpers no)
		(fp_line
			(start -0.7874 -0.4064)
			(end -0.7874 0.4064)
			(stroke
				(width 0.1524)
				(type default)
			)
			(layer "B.SilkS")
		)
		(fp_line
			(start -0.7874 0.4064)
			(end 0.7874 0.4064)
			(stroke
				(width 0.1524)
				(type default)
			)
			(layer "B.SilkS")
		)
		(fp_line
			(start 0.7874 -0.4064)
			(end -0.7874 -0.4064)
			(stroke
				(width 0.1524)
				(type default)
			)
			(layer "B.SilkS")
		)
		(fp_line
			(start 0.7874 0.4064)
			(end 0.7874 -0.4064)
			(stroke
				(width 0.1524)
				(type default)
			)
			(layer "B.SilkS")
		)
		(fp_line
			(start -0.67945 -0.3048)
			(end -0.67945 0.3048)
			(stroke
				(width 0.1)
				(type default)
			)
			(layer "B.Fab")
		)
		(fp_line
			(start -0.67945 0.3048)
			(end -0.120396 0.3048)
			(stroke
				(width 0.1)
				(type default)
			)
			(layer "B.Fab")
		)
		(fp_line
			(start -0.12065 -0.3048)
			(end -0.67945 -0.3048)
			(stroke
				(width 0.1)
				(type default)
			)
			(layer "B.Fab")
		)
		(fp_line
			(start -0.12065 -0.2794)
			(end -0.12065 -0.3048)
			(stroke
				(width 0.1)
				(type default)
			)
			(layer "B.Fab")
		)
		(fp_line
			(start -0.120396 0.2794)
			(end 0.12065 0.2794)
			(stroke
				(width 0.1)
				(type default)
			)
			(layer "B.Fab")
		)
		(fp_line
			(start -0.120396 0.3048)
			(end -0.120396 0.2794)
			(stroke
				(width 0.1)
				(type default)
			)
			(layer "B.Fab")
		)
		(fp_line
			(start 0.12065 -0.305054)
			(end 0.12065 -0.2794)
			(stroke
				(width 0.1)
				(type default)
			)
			(layer "B.Fab")
		)
		(fp_line
			(start 0.12065 -0.2794)
			(end -0.12065 -0.2794)
			(stroke
				(width 0.1)
				(type default)
			)
			(layer "B.Fab")
		)
		(fp_line
			(start 0.12065 0.2794)
			(end 0.12065 0.3048)
			(stroke
				(width 0.1)
				(type default)
			)
			(layer "B.Fab")
		)
		(fp_line
			(start 0.12065 0.3048)
			(end 0.67945 0.3048)
			(stroke
				(width 0.1)
				(type default)
			)
			(layer "B.Fab")
		)
		(fp_line
			(start 0.67945 -0.305054)
			(end 0.12065 -0.305054)
			(stroke
				(width 0.1)
				(type default)
			)
			(layer "B.Fab")
		)
		(fp_line
			(start 0.67945 0.3048)
			(end 0.67945 -0.305054)
			(stroke
				(width 0.1)
				(type default)
			)
			(layer "B.Fab")
		)
		(pad "1" smd circle
			(at 0.40005 0 180)
			(size 0 0)
			(layers "B.Cu" "B.Mask" "B.Paste")
			(net "P3V3_AUX")
		)
		(pad "2" smd circle
			(at -0.40005 0 180)
			(size 0 0)
			(layers "B.Cu" "B.Mask" "B.Paste")
			(net "FM_PCH_PRSNT_N")
		)
	)
	(footprint ""
		(layer "B.Cu")
		(at 131.93522 -24.895048 180)
		(property "Reference" "C2290"
			(at 0 0 0)
			(layer "B.SilkS")
			(hide yes)
			(effects
				(font
					(size 1.27 1.27)
				)
				(justify mirror)
			)
		)
		(property "Value" ""
			(at 0 0 0)
			(layer "B.Fab")
			(effects
				(font
					(size 1.27 1.27)
				)
				(justify mirror)
			)
		)
		(duplicate_pad_numbers_are_jumpers no)
		(fp_line
			(start 0.299974 0.150114)
			(end 0.299974 -0.150114)
			(stroke
				(width 0.1)
				(type default)
			)
			(layer "B.Fab")
		)
		(fp_line
			(start 0.299974 -0.150114)
			(end -0.299974 -0.150114)
			(stroke
				(width 0.1)
				(type default)
			)
			(layer "B.Fab")
		)
		(fp_line
			(start -0.299974 0.150114)
			(end 0.299974 0.150114)
			(stroke
				(width 0.1)
				(type default)
			)
			(layer "B.Fab")
		)
		(fp_line
			(start -0.299974 -0.150114)
			(end -0.299974 0.150114)
			(stroke
				(width 0.1)
				(type default)
			)
			(layer "B.Fab")
		)
		(pad "1" smd rect
			(at 0.2667 0)
			(size 0.3048 0.381)
			(layers "B.Cu" "B.Mask" "B.Paste")
			(net "USB3_PCH_TX_BUF_DN<4>")
		)
		(pad "2" smd rect
			(at -0.2667 0)
			(size 0.3048 0.381)
			(layers "B.Cu" "B.Mask" "B.Paste")
			(net "USB3_PCH_TX_BUF_C_DN<4>")
		)
	)
	(footprint ""
		(layer "B.Cu")
		(at 73.316084 -190.719456 -90)
		(property "Reference" "R559"
			(at 0 0 90)
			(layer "B.SilkS")
			(hide yes)
			(effects
				(font
					(size 1.27 1.27)
				)
				(justify mirror)
			)
		)
		(property "Value" ""
			(at 0 0 90)
			(layer "B.Fab")
			(effects
				(font
					(size 1.27 1.27)
				)
				(justify mirror)
			)
		)
		(duplicate_pad_numbers_are_jumpers no)
		(fp_line
			(start -0.7874 0.4064)
			(end 0.7874 0.4064)
			(stroke
				(width 0.1524)
				(type default)
			)
			(layer "B.SilkS")
		)
		(fp_line
			(start 0.7874 0.4064)
			(end 0.7874 -0.4064)
			(stroke
				(width 0.1524)
				(type default)
			)
			(layer "B.SilkS")
		)
		(fp_line
			(start -0.7874 -0.4064)
			(end -0.7874 0.4064)
			(stroke
				(width 0.1524)
				(type default)
			)
			(layer "B.SilkS")
		)
		(fp_line
			(start 0.7874 -0.4064)
			(end -0.7874 -0.4064)
			(stroke
				(width 0.1524)
				(type default)
			)
			(layer "B.SilkS")
		)
		(fp_line
			(start -0.67945 0.3048)
			(end -0.120396 0.3048)
			(stroke
				(width 0.1)
				(type default)
			)
			(layer "B.Fab")
		)
		(fp_line
			(start -0.120396 0.3048)
			(end -0.120396 0.2794)
			(stroke
				(width 0.1)
				(type default)
			)
			(layer "B.Fab")
		)
		(fp_line
			(start 0.12065 0.3048)
			(end 0.67945 0.3048)
			(stroke
				(width 0.1)
				(type default)
			)
			(layer "B.Fab")
		)
		(fp_line
			(start 0.67945 0.3048)
			(end 0.67945 -0.305054)
			(stroke
				(width 0.1)
				(type default)
			)
			(layer "B.Fab")
		)
		(fp_line
			(start -0.120396 0.2794)
			(end 0.12065 0.2794)
			(stroke
				(width 0.1)
				(type default)
			)
			(layer "B.Fab")
		)
		(fp_line
			(start 0.12065 0.2794)
			(end 0.12065 0.3048)
			(stroke
				(width 0.1)
				(type default)
			)
			(layer "B.Fab")
		)
		(fp_line
			(start -0.12065 -0.2794)
			(end -0.12065 -0.3048)
			(stroke
				(width 0.1)
				(type default)
			)
			(layer "B.Fab")
		)
		(fp_line
			(start 0.12065 -0.2794)
			(end -0.12065 -0.2794)
			(stroke
				(width 0.1)
				(type default)
			)
			(layer "B.Fab")
		)
		(fp_line
			(start -0.67945 -0.3048)
			(end -0.67945 0.3048)
			(stroke
				(width 0.1)
				(type default)
			)
			(layer "B.Fab")
		)
		(fp_line
			(start -0.12065 -0.3048)
			(end -0.67945 -0.3048)
			(stroke
				(width 0.1)
				(type default)
			)
			(layer "B.Fab")
		)
		(fp_line
			(start 0.12065 -0.305054)
			(end 0.12065 -0.2794)
			(stroke
				(width 0.1)
				(type default)
			)
			(layer "B.Fab")
		)
		(fp_line
			(start 0.67945 -0.305054)
			(end 0.12065 -0.305054)
			(stroke
				(width 0.1)
				(type default)
			)
			(layer "B.Fab")
		)
		(pad "1" smd circle
			(at 0.40005 0 90)
			(size 0 0)
			(layers "B.Cu" "B.Mask" "B.Paste")
			(net "SVID_DIO1_CPU1_R")
		)
		(pad "2" smd circle
			(at -0.40005 0 90)
			(size 0 0)
			(layers "B.Cu" "B.Mask" "B.Paste")
			(net "PVNN_TERM_CPU1")
		)
	)
)
